# T6G (Grand Teton) — schematic netlist excerpt (pin names and nets, part order shuffled) for the footprints in the layout excerpt that follows; sources: Cadence DE-HDL packaged netlist, KiCad conversion of 04192023_DAF0TMB3IC0_F0TG_MB_C_brd_V02_OCP.brd

J1  SCONN288_DDR506112002KQ  IO  pkg DDR288S_1-1VXC  page 86
  VIN_BULK0  = P12V_MEM_CPU0
  RFU0  = NC
  VIN_MGMT  = P3V3_AUX
  HSCL  = I3C_SPD_DDRA_CPU0_SCL
  HSDA  = I3C_SPD_DDRA_CPU0_SDA
  VSS0  = GND
  DQ0_A  = M_A_CPU0_SA_DQ<0>
  VSS1  = GND
  DQ1_A  = M_A_CPU0_SA_DQ<1>
  VSS2  = GND
  DQS0_A_T  = M_A_CPU0_SA_DQS_DP<0>
  DQS0_A_C  = M_A_CPU0_SA_DQS_DN<0>
  VSS3  = GND
  DQ4_A  = M_A_CPU0_SA_DQ<4>
  VSS4  = GND
  DQ5_A  = M_A_CPU0_SA_DQ<5>
  VSS5  = GND
  DQ8_A  = M_A_CPU0_SA_DQ<8>
  VSS6  = GND
  DQ9_A  = M_A_CPU0_SA_DQ<9>
  VSS7  = GND
  DQS1_A_T  = M_A_CPU0_SA_DQS_DP<1>
  DQS1_A_C  = M_A_CPU0_SA_DQS_DN<1>
  VSS8  = GND
  DQ12_A  = M_A_CPU0_SA_DQ<12>
  VSS9  = GND
  DQ13_A  = M_A_CPU0_SA_DQ<13>
  VSS10  = GND
  DQ16_A  = M_A_CPU0_SA_DQ<16>
  VSS11  = GND
  DQ17_A  = M_A_CPU0_SA_DQ<17>
  VSS12  = GND
  DQS2_A_T  = M_A_CPU0_SA_DQS_DP<2>
  DQS2_A_C  = M_A_CPU0_SA_DQS_DN<2>
  VSS13  = GND
  DQ20_A  = M_A_CPU0_SA_DQ<20>
  VSS14  = GND
  DQ21_A  = M_A_CPU0_SA_DQ<21>
  VSS15  = GND
  DQ24_A  = M_A_CPU0_SA_DQ<24>
  VSS16  = GND
  DQ25_A  = M_A_CPU0_SA_DQ<25>
  VSS17  = GND
  DQS3_A_T  = M_A_CPU0_SA_DQS_DP<3>
  DQS3_A_C  = M_A_CPU0_SA_DQS_DN<3>
  VSS18  = GND
  DQ28_A  = M_A_CPU0_SA_DQ<28>
  VSS19  = GND
  DQ29_A  = M_A_CPU0_SA_DQ<29>
  VSS20  = GND
  CB0_A  = M_A_CPU0_SA_CB<0>
  VSS21  = GND
  CB1_A  = M_A_CPU0_SA_CB<1>
  VSS22  = GND
  DQS4_A_T  = M_A_CPU0_SA_DQS_DP<4>
  DQS4_A_C  = M_A_CPU0_SA_DQS_DN<4>
  VSS23  = GND
  CB4_A  = M_A_CPU0_SA_CB<4>
  VSS24  = GND
  CB5_A  = M_A_CPU0_SA_CB<5>
  VSS25  = GND
  ALERT_N  = M_A_CPU0_ALERT_N
  VSS26  = GND
  CS0_A_N  = M_A_CPU0_SA_CS_N<0>
  VSS27  = GND
  CA0_A  = M_A_CPU0_SA_CA<0>
  VSS28  = GND
  CA2_A  = M_A_CPU0_SA_CA<2>
  VSS29  = GND
  CA4_A  = M_A_CPU0_SA_CA<4>
  VSS30  = GND
  CA6_A  = M_A_CPU0_SA_CA<6>
  VSS31  = GND
  PAR_A  = M_A_CPU0_SA_PAR
  VSS32  = GND
  CA0_B  = M_A_CPU0_SB_CA<0>
  VSS33  = GND
  CA2_B  = M_A_CPU0_SB_CA<2>
  VSS34  = GND
  CA4_B  = M_A_CPU0_SB_CA<4>
  VSS35  = GND
  CA6_B  = M_A_CPU0_SB_CA<6>
  VSS36  = GND
  CS0_B_N  = M_A_CPU0_SB_CS_N<0>
  VSS37  = GND
  \lbd||rsp_a_n\  = M_A_CPU0_SA_RSP<0>
  \lbs||rsp_b_n\  = M_A_CPU0_SB_RSP<0>
  VSS38  = GND
  CB4_B  = M_A_CPU0_SB_CB<4>
  VSS39  = GND
  CB5_B  = M_A_CPU0_SB_CB<5>
  VSS40  = GND
  \dqs9_b_t||tdqs9_b_t||dbi4_b_n\  = M_A_CPU0_SB_DQS_DP<9>
  \dqs9_b_c||tdqs9_b_c\  = M_A_CPU0_SB_DQS_DN<9>
  VSS41  = GND
  CB0_B  = M_A_CPU0_SB_CB<0>
  VSS42  = GND
  CB1_B  = M_A_CPU0_SB_CB<1>
  VSS43  = GND
  DQ0_B  = M_A_CPU0_SB_DQ<0>
  VSS44  = GND
  DQ1_B  = M_A_CPU0_SB_DQ<1>
  VSS45  = GND
  DQS0_B_T  = M_A_CPU0_SB_DQS_DP<0>
  DQS0_B_C  = M_A_CPU0_SB_DQS_DN<0>
  VSS46  = GND
  DQ4_B  = M_A_CPU0_SB_DQ<4>
  VSS47  = GND
  DQ5_B  = M_A_CPU0_SB_DQ<5>
  VSS48  = GND
  DQ8_B  = M_A_CPU0_SB_DQ<8>
  VSS49  = GND
  DQ9_B  = M_A_CPU0_SB_DQ<9>
  VSS50  = GND
  DQS1_B_T  = M_A_CPU0_SB_DQS_DP<1>
  DQS1_B_C  = M_A_CPU0_SB_DQS_DN<1>
  VSS51  = GND
  DQ12_B  = M_A_CPU0_SB_DQ<12>
  VSS52  = GND
  DQ13_B  = M_A_CPU0_SB_DQ<13>
  VSS53  = GND
  DQ16_B  = M_A_CPU0_SB_DQ<16>
  VSS54  = GND
  DQ17_B  = M_A_CPU0_SB_DQ<17>
  VSS55  = GND
  DQS2_B_T  = M_A_CPU0_SB_DQS_DP<2>
  DQS2_B_C  = M_A_CPU0_SB_DQS_DN<2>
  VSS56  = GND
  DQ20_B  = M_A_CPU0_SB_DQ<20>
  VSS57  = GND
  DQ21_B  = M_A_CPU0_SB_DQ<21>
  VSS58  = GND
  DQ24_B  = M_A_CPU0_SB_DQ<24>
  VSS59  = GND
  DQ25_B  = M_A_CPU0_SB_DQ<25>
  VSS60  = GND
  DQS3_B_T  = M_A_CPU0_SB_DQS_DP<3>
  DQS3_B_C  = M_A_CPU0_SB_DQS_DN<3>
  VSS61  = GND
  DQ28_B  = M_A_CPU0_SB_DQ<28>
  VSS62  = GND
  DQ29_B  = M_A_CPU0_SB_DQ<29>
  VSS63  = GND
  RFU1  = NC
  VIN_BULK1  = P12V_MEM_CPU0
  VIN_BULK2  = P12V_MEM_CPU0
  \pwr_good||fail_n\  = PWRGD_CHA_CPU0_DIMM0
  HAS  = PD_CHA_CPU0_DIMM0_SAA
  RFU2  = NC
  RFU3  = NC
  VSS64  = GND
  DQ2_A  = M_A_CPU0_SA_DQ<2>
  VSS65  = GND
  DQ3_A  = M_A_CPU0_SA_DQ<3>
  VSS66  = GND
  \dqs5_a_c||tdqs5_a_c||dqs5_a_t||tdqs5_a_t\  = M_A_CPU0_SA_DQS_DN<5>
  \dqs5_a_t||tdqs5_a_t\  = M_A_CPU0_SA_DQS_DP<5>
  VSS67  = GND
  DQ6_A  = M_A_CPU0_SA_DQ<6>
  VSS68  = GND
  DQ7_A  = M_A_CPU0_SA_DQ<7>
  VSS69  = GND
  DQ10_A  = M_A_CPU0_SA_DQ<10>
  VSS70  = GND
  DQ11_A  = M_A_CPU0_SA_DQ<11>
  VSS71  = GND
  \dqs6_a_c||tdqs6_a_c||dqs6_a_t||tdqs6_a_t\  = M_A_CPU0_SA_DQS_DN<6>
  \dqs6_a_t||tdqs6_a_t\  = M_A_CPU0_SA_DQS_DP<6>
  VSS72  = GND
  DQ14_A  = M_A_CPU0_SA_DQ<14>
  VSS73  = GND
  DQ15_A  = M_A_CPU0_SA_DQ<15>
  VSS74  = GND
  DQ18_A  = M_A_CPU0_SA_DQ<18>
  VSS75  = GND
  DQ19_A  = M_A_CPU0_SA_DQ<19>
  VSS76  = GND
  \dqs7_a_c||tdqs7_a_c\  = M_A_CPU0_SA_DQS_DN<7>
  \dqs7_a_t||tdqs7_a_t\  = M_A_CPU0_SA_DQS_DP<7>
  VSS77  = GND
  DQ22_A  = M_A_CPU0_SA_DQ<22>
  VSS78  = GND
  DQ23_A  = M_A_CPU0_SA_DQ<23>
  VSS79  = GND
  DQ26_A  = M_A_CPU0_SA_DQ<26>
  VSS80  = GND
  DQ27_A  = M_A_CPU0_SA_DQ<27>
  VSS81  = GND
  \dqs8_a_c||tdqs8_a_c\  = M_A_CPU0_SA_DQS_DN<8>
  \dqs8_a_t||tdqs8_a_t\  = M_A_CPU0_SA_DQS_DP<8>
  VSS82  = GND
  DQ30_A  = M_A_CPU0_SA_DQ<30>
  VSS83  = GND
  DQ31_A  = M_A_CPU0_SA_DQ<31>
  VSS84  = GND
  CB2_A  = M_A_CPU0_SA_CB<2>
  VSS85  = GND
  CB3_A  = M_A_CPU0_SA_CB<3>
  VSS86  = GND
  \dqs9_a_c||tdqs9_a_c\  = M_A_CPU0_SA_DQS_DN<9>
  \dqs9_a_t||tdqs9_a_t\  = M_A_CPU0_SA_DQS_DP<9>
  VSS87  = GND
  CB6_A  = M_A_CPU0_SA_CB<6>
  VSS88  = GND
  CB7_A  = M_A_CPU0_SA_CB<7>
  VSS89  = GND
  RESET_N  = M_A_CPU0_RESET_N
  VSS90  = GND
  CS1_A_N  = M_A_CPU0_SA_CS_N<1>
  VSS91  = GND
  CA1_A  = M_A_CPU0_SA_CA<1>
  VSS92  = GND
  CA3_A  = M_A_CPU0_SA_CA<3>
  VSS93  = GND
  CA5_A  = M_A_CPU0_SA_CA<5>
  VSS94  = GND
  CK_T  = M_A_CPU0_CLK_DP<0>
  CK_C  = M_A_CPU0_CLK_DN<0>
  VSS95  = GND
  RFU4  = NC
  CA1_B  = M_A_CPU0_SB_CA<1>
  VSS96  = GND
  CA3_B  = M_A_CPU0_SB_CA<3>
  VSS97  = GND
  CA5_B  = M_A_CPU0_SB_CA<5>
  VSS98  = GND
  PAR_B  = M_A_CPU0_SB_PAR
  VSS99  = GND
  CS1_B_N  = M_A_CPU0_SB_CS_N<1>
  VSS100  = GND
  RFU5  = NC
  RFU6  = NC
  VSS101  = GND
  CB6_B  = M_A_CPU0_SB_CB<6>
  VSS102  = GND
  CB7_B  = M_A_CPU0_SB_CB<7>
  VSS103  = GND
  DQS4_B_C  = M_A_CPU0_SB_DQS_DN<4>
  DQS4_B_T  = M_A_CPU0_SB_DQS_DP<4>
  VSS104  = GND
  CB2_B  = M_A_CPU0_SB_CB<2>
  VSS105  = GND
  CB3_B  = M_A_CPU0_SB_CB<3>
  VSS106  = GND
  DQ2_B  = M_A_CPU0_SB_DQ<2>
  VSS107  = GND
  DQ3_B  = M_A_CPU0_SB_DQ<3>
  VSS108  = GND
  \dqs5_b_c||tdqs5_b_c\  = M_A_CPU0_SB_DQS_DN<5>
  \dqs5_b_t||tdqs5_b_t\  = M_A_CPU0_SB_DQS_DP<5>
  VSS109  = GND
  DQ6_B  = M_A_CPU0_SB_DQ<6>
  VSS110  = GND
  DQ7_B  = M_A_CPU0_SB_DQ<7>
  VSS111  = GND
  DQ10_B  = M_A_CPU0_SB_DQ<10>
  VSS112  = GND
  DQ11_B  = M_A_CPU0_SB_DQ<11>
  VSS113  = GND
  \dqs6_b_c||tdqs6_b_c\  = M_A_CPU0_SB_DQS_DN<6>
  \dqs6_b_t||tdqs6_b_t\  = M_A_CPU0_SB_DQS_DP<6>
  VSS114  = GND
  DQ14_B  = M_A_CPU0_SB_DQ<14>
  VSS115  = GND
  DQ15_B  = M_A_CPU0_SB_DQ<15>
  VSS116  = GND
  DQ18_B  = M_A_CPU0_SB_DQ<18>
  VSS117  = GND
  DQ19_B  = M_A_CPU0_SB_DQ<19>
  VSS118  = GND
  \dqs7_b_c||tdqs7_b_c\  = M_A_CPU0_SB_DQS_DN<7>
  \dqs7_b_t||tdqs7_b_t\  = M_A_CPU0_SB_DQS_DP<7>
  VSS119  = GND
  DQ22_B  = M_A_CPU0_SB_DQ<22>
  VSS120  = GND
  DQ23_B  = M_A_CPU0_SB_DQ<23>
  VSS121  = GND
  DQ26_B  = M_A_CPU0_SB_DQ<26>
  VSS122  = GND
  DQ27_B  = M_A_CPU0_SB_DQ<27>
  VSS123  = GND
  \dqs8_b_c||tdqs8_b_c\  = M_A_CPU0_SB_DQS_DN<8>
  \dqs8_b_t||tdqs8_b_t\  = M_A_CPU0_SB_DQS_DP<8>
  VSS124  = GND
  DQ30_B  = M_A_CPU0_SB_DQ<30>
  VSS125  = GND
  DQ31_B  = M_A_CPU0_SB_DQ<31>
  VSS126  = GND
  G1  = GND
  G2  = GND
  G3  = GND

(kicad_pcb
	(version 20260206)
	(generator "pcbnew")
	(generator_version "10.0")
	(general
		(thickness 1.6)
		(legacy_teardrops no)
	)
	(paper "A4")
	(title_block
		(title "04192023_DAF0TMB3IC0_F0TG_MB_C_brd_V02_OCP.brd")
		(comment 1 "Grand Teton / footprint 2352 of 8354 (J1), pads 277-291 of 291")
	)
	(layers
		(0 "F.Cu" signal "TOP")
		(4 "In1.Cu" signal "GND")
		(6 "In2.Cu" signal "IN1")
		(8 "In3.Cu" signal "GND1")
		(10 "In4.Cu" signal "IN2")
		(12 "In5.Cu" signal "GND2")
		(14 "In6.Cu" signal "IN3")
		(16 "In7.Cu" signal "GND3")
		(18 "In8.Cu" signal "VCC")
		(20 "In9.Cu" signal "VCC1")
		(22 "In10.Cu" signal "GND4")
		(24 "In11.Cu" signal "IN4")
		(26 "In12.Cu" signal "GND5")
		(28 "In13.Cu" signal "IN5")
		(30 "In14.Cu" signal "GND6")
		(32 "In15.Cu" signal "IN6")
		(34 "In16.Cu" signal "GND7")
		(2 "B.Cu" signal "BOTTOM")
		(9 "F.Adhes" user "F.Adhesive")
		(11 "B.Adhes" user "B.Adhesive")
		(13 "F.Paste" user "Package Geometry/Pastemask Top")
		(15 "B.Paste" user "Package Geometry/Pastemask Bottom")
		(5 "F.SilkS" user "Ref Des/Silkscreen Top")
		(7 "B.SilkS" user "Ref Des/Silkscreen Bottom")
		(1 "F.Mask" user "Board Geometry/Soldermask Top")
		(3 "B.Mask" user "Board Geometry/Soldermask Bottom")
		(17 "Dwgs.User" user "User.Drawings")
		(19 "Cmts.User" user "User.Comments")
		(21 "Eco1.User" user "User.Eco1")
		(23 "Eco2.User" user "User.Eco2")
		(25 "Edge.Cuts" user "Board Geometry/Outline")
		(27 "Margin" user)
		(31 "F.CrtYd" user "Package Geometry/Place Bound Top")
		(29 "B.CrtYd" user "Package Geometry/Place Bound Bottom")
		(35 "F.Fab" user "Ref Des/Assembly Top")
		(33 "B.Fab" user "Ref Des/Assembly Bottom")
	)
	(footprint ""
		(layer "F.Cu")
		(at 305.31816 -255.560068 180)
		(property "Reference" "J1"
			(at -2.2098 -81.984088 0)
			(unlocked yes)
			(layer "F.SilkS")
			(effects
				(font
					(size 0.7874 0.5842)
					(thickness 0.1524)
				)
			)
		)
		(property "Value" ""
			(at 0 0 180)
			(layer "F.Fab")
			(effects
				(font
					(size 1.27 1.27)
				)
			)
		)
		(duplicate_pad_numbers_are_jumpers no)
		(pad "277" smd rect
			(at 2.050034 53.975 90)
			(size 0.519938 1.4986)
			(layers "F.Cu" "F.Mask" "F.Paste")
			(net "GND")
		)
		(pad "278" smd rect
			(at 2.050034 54.824884 90)
			(size 0.519938 1.4986)
			(layers "F.Cu" "F.Mask" "F.Paste")
			(net "M_A_CPU0_SB_DQ<26>")
		)
		(pad "279" smd rect
			(at 2.050034 55.675022 90)
			(size 0.519938 1.4986)
			(layers "F.Cu" "F.Mask" "F.Paste")
			(net "GND")
		)
		(pad "280" smd rect
			(at 2.050034 56.524906 90)
			(size 0.519938 1.4986)
			(layers "F.Cu" "F.Mask" "F.Paste")
			(net "M_A_CPU0_SB_DQ<27>")
		)
		(pad "281" smd rect
			(at 2.050034 57.375044 90)
			(size 0.519938 1.4986)
			(layers "F.Cu" "F.Mask" "F.Paste")
			(net "GND")
		)
		(pad "282" smd rect
			(at 2.050034 58.224928 90)
			(size 0.519938 1.4986)
			(layers "F.Cu" "F.Mask" "F.Paste")
			(net "M_A_CPU0_SB_DQS_DN<8>")
		)
		(pad "283" smd rect
			(at 2.050034 59.075066 90)
			(size 0.519938 1.4986)
			(layers "F.Cu" "F.Mask" "F.Paste")
			(net "M_A_CPU0_SB_DQS_DP<8>")
		)
		(pad "284" smd rect
			(at 2.050034 59.92495 90)
			(size 0.519938 1.4986)
			(layers "F.Cu" "F.Mask" "F.Paste")
			(net "GND")
		)
		(pad "285" smd rect
			(at 2.050034 60.775088 90)
			(size 0.519938 1.4986)
			(layers "F.Cu" "F.Mask" "F.Paste")
			(net "M_A_CPU0_SB_DQ<30>")
		)
		(pad "286" smd rect
			(at 2.050034 61.624972 90)
			(size 0.519938 1.4986)
			(layers "F.Cu" "F.Mask" "F.Paste")
			(net "GND")
		)
		(pad "287" smd rect
			(at 2.050034 62.47511 90)
			(size 0.519938 1.4986)
			(layers "F.Cu" "F.Mask" "F.Paste")
			(net "M_A_CPU0_SB_DQ<31>")
		)
		(pad "288" smd rect
			(at 2.050034 63.324994 90)
			(size 0.519938 1.4986)
			(layers "F.Cu" "F.Mask" "F.Paste")
			(net "GND")
		)
		(pad "G1" thru_hole oval
			(at 0 -68.97497 90)
			(size 1.7272 3.4798)
			(drill oval 1.2192 2.4638)
			(layers "*.Cu" "*.Mask")
			(remove_unused_layers no)
			(net "GND")
			(clearance 0.127)
			(thermal_gap 0.127)
		)
		(pad "G2" thru_hole oval
			(at 0 3.875024 90)
			(size 1.7272 3.4798)
			(drill oval 1.2192 2.4638)
			(layers "*.Cu" "*.Mask")
			(remove_unused_layers no)
			(net "GND")
			(clearance 0.127)
			(thermal_gap 0.127)
		)
		(pad "G3" thru_hole oval
			(at 0 68.97497 90)
			(size 1.7272 3.4798)
			(drill oval 1.2192 2.4638)
			(layers "*.Cu" "*.Mask")
			(remove_unused_layers no)
			(net "GND")
			(clearance 0.127)
			(thermal_gap 0.127)
		)
	)
)
